# S9S_MB_2U (Grand Teton) — schematic netlist excerpt (pin names and nets, part order shuffled) for the footprints in the layout excerpt that follows; sources: Cadence DE-HDL packaged netlist, KiCad conversion of 03242023_DA0F0TMBIJ0_F0T_Motherboard_J_brd_V01_OCP.brd

PC1596  Q_CAPP  560UF 2.5V 20% OSCON  pkg THLF  page 293 : A = PVCCINFAON_CPU1 ; B = GND
R3275  Q_RES  1K 1% EMPTY  pkg 0402LF  page 166 : A = P3V3_AUX ; B = FM_P2E_FGA
PC176  Q_CAP  3300PF 50V 10% X7R  pkg 0402  page 276 : A = SW_P12V_PVCCINFAON_CPU0_FLT ; B = GND

(kicad_pcb
	(version 20260206)
	(generator "pcbnew")
	(generator_version "10.0")
	(general
		(thickness 1.6)
		(legacy_teardrops no)
	)
	(paper "A4")
	(title_block
		(title "03242023_DA0F0TMBIJ0_F0T_Motherboard_J_brd_V01_OCP.brd")
		(comment 1 "Grand Teton / footprints 2948-2950 of 6105")
	)
	(layers
		(0 "F.Cu" signal "TOP")
		(4 "In1.Cu" signal "GND")
		(6 "In2.Cu" signal "IN1")
		(8 "In3.Cu" signal "GND1")
		(10 "In4.Cu" signal "IN2")
		(12 "In5.Cu" signal "GND2")
		(14 "In6.Cu" signal "IN3")
		(16 "In7.Cu" signal "GND3")
		(18 "In8.Cu" signal "VCC")
		(20 "In9.Cu" signal "VCC1")
		(22 "In10.Cu" signal "GND4")
		(24 "In11.Cu" signal "IN4")
		(26 "In12.Cu" signal "GND5")
		(28 "In13.Cu" signal "IN5")
		(30 "In14.Cu" signal "GND6")
		(32 "In15.Cu" signal "IN6")
		(34 "In16.Cu" signal "GND7")
		(2 "B.Cu" signal "BOTTOM")
		(9 "F.Adhes" user "F.Adhesive")
		(11 "B.Adhes" user "B.Adhesive")
		(13 "F.Paste" user "Package Geometry/Pastemask Top")
		(15 "B.Paste" user "Package Geometry/Pastemask Bottom")
		(5 "F.SilkS" user "Ref Des/Silkscreen Top")
		(7 "B.SilkS" user "Ref Des/Silkscreen Bottom")
		(1 "F.Mask" user "Board Geometry/Soldermask Top")
		(3 "B.Mask" user "Board Geometry/Soldermask Bottom")
		(17 "Dwgs.User" user "User.Drawings")
		(19 "Cmts.User" user "User.Comments")
		(21 "Eco1.User" user "User.Eco1")
		(23 "Eco2.User" user "User.Eco2")
		(25 "Edge.Cuts" user "Board Geometry/Outline")
		(27 "Margin" user)
		(31 "F.CrtYd" user "Package Geometry/Place Bound Top")
		(29 "B.CrtYd" user "Package Geometry/Place Bound Bottom")
		(35 "F.Fab" user "Ref Des/Assembly Top")
		(33 "B.Fab" user "Ref Des/Assembly Bottom")
	)
	(footprint ""
		(layer "F.Cu")
		(at 15.436596 -391.183876)
		(property "Reference" "R3275"
			(at 0 0 0)
			(layer "F.SilkS")
			(hide yes)
			(effects
				(font
					(size 1.27 1.27)
				)
			)
		)
		(property "Value" ""
			(at 0 0 0)
			(layer "F.Fab")
			(effects
				(font
					(size 1.27 1.27)
				)
			)
		)
		(duplicate_pad_numbers_are_jumpers no)
		(fp_line
			(start -0.7874 -0.4064)
			(end 0.7874 -0.4064)
			(stroke
				(width 0.1524)
				(type default)
			)
			(layer "F.SilkS")
		)
		(fp_line
			(start -0.7874 0.4064)
			(end -0.7874 -0.4064)
			(stroke
				(width 0.1524)
				(type default)
			)
			(layer "F.SilkS")
		)
		(fp_line
			(start 0.7874 -0.4064)
			(end 0.7874 0.4064)
			(stroke
				(width 0.1524)
				(type default)
			)
			(layer "F.SilkS")
		)
		(fp_line
			(start 0.7874 0.4064)
			(end -0.7874 0.4064)
			(stroke
				(width 0.1524)
				(type default)
			)
			(layer "F.SilkS")
		)
		(fp_line
			(start -0.67945 -0.305054)
			(end -0.12065 -0.305054)
			(stroke
				(width 0.1)
				(type default)
			)
			(layer "F.Fab")
		)
		(fp_line
			(start -0.67945 0.3048)
			(end -0.67945 -0.305054)
			(stroke
				(width 0.1)
				(type default)
			)
			(layer "F.Fab")
		)
		(fp_line
			(start -0.12065 -0.305054)
			(end -0.12065 -0.2794)
			(stroke
				(width 0.1)
				(type default)
			)
			(layer "F.Fab")
		)
		(fp_line
			(start -0.12065 -0.2794)
			(end 0.12065 -0.2794)
			(stroke
				(width 0.1)
				(type default)
			)
			(layer "F.Fab")
		)
		(fp_line
			(start -0.12065 0.2794)
			(end -0.12065 0.3048)
			(stroke
				(width 0.1)
				(type default)
			)
			(layer "F.Fab")
		)
		(fp_line
			(start -0.12065 0.3048)
			(end -0.67945 0.3048)
			(stroke
				(width 0.1)
				(type default)
			)
			(layer "F.Fab")
		)
		(fp_line
			(start 0.120396 0.2794)
			(end -0.12065 0.2794)
			(stroke
				(width 0.1)
				(type default)
			)
			(layer "F.Fab")
		)
		(fp_line
			(start 0.120396 0.3048)
			(end 0.120396 0.2794)
			(stroke
				(width 0.1)
				(type default)
			)
			(layer "F.Fab")
		)
		(fp_line
			(start 0.12065 -0.3048)
			(end 0.67945 -0.3048)
			(stroke
				(width 0.1)
				(type default)
			)
			(layer "F.Fab")
		)
		(fp_line
			(start 0.12065 -0.2794)
			(end 0.12065 -0.3048)
			(stroke
				(width 0.1)
				(type default)
			)
			(layer "F.Fab")
		)
		(fp_line
			(start 0.67945 -0.3048)
			(end 0.67945 0.3048)
			(stroke
				(width 0.1)
				(type default)
			)
			(layer "F.Fab")
		)
		(fp_line
			(start 0.67945 0.3048)
			(end 0.120396 0.3048)
			(stroke
				(width 0.1)
				(type default)
			)
			(layer "F.Fab")
		)
		(pad "1" smd circle
			(at -0.40005 0)
			(size 0 0)
			(layers "F.Cu" "F.Mask" "F.Paste")
			(net "P3V3_AUX")
		)
		(pad "2" smd circle
			(at 0.40005 0)
			(size 0 0)
			(layers "F.Cu" "F.Mask" "F.Paste")
			(net "FM_P2E_FGA")
		)
	)
	(footprint ""
		(layer "F.Cu")
		(at 423.089324 -149.239224 -90)
		(property "Reference" "PC176"
			(at 0 0 270)
			(layer "F.SilkS")
			(hide yes)
			(effects
				(font
					(size 1.27 1.27)
				)
			)
		)
		(property "Value" ""
			(at 0 0 270)
			(layer "F.Fab")
			(effects
				(font
					(size 1.27 1.27)
				)
			)
		)
		(duplicate_pad_numbers_are_jumpers no)
		(fp_line
			(start -0.7874 0.4064)
			(end -0.7874 -0.4064)
			(stroke
				(width 0.1524)
				(type default)
			)
			(layer "F.SilkS")
		)
		(fp_line
			(start 0.7874 0.4064)
			(end -0.7874 0.4064)
			(stroke
				(width 0.1524)
				(type default)
			)
			(layer "F.SilkS")
		)
		(fp_line
			(start -0.7874 -0.4064)
			(end 0.7874 -0.4064)
			(stroke
				(width 0.1524)
				(type default)
			)
			(layer "F.SilkS")
		)
		(fp_line
			(start 0.7874 -0.4064)
			(end 0.7874 0.4064)
			(stroke
				(width 0.1524)
				(type default)
			)
			(layer "F.SilkS")
		)
		(fp_line
			(start -0.67945 0.3048)
			(end -0.67945 -0.305054)
			(stroke
				(width 0.1)
				(type default)
			)
			(layer "F.Fab")
		)
		(fp_line
			(start -0.12065 0.3048)
			(end -0.67945 0.3048)
			(stroke
				(width 0.1)
				(type default)
			)
			(layer "F.Fab")
		)
		(fp_line
			(start 0.120396 0.3048)
			(end 0.120396 0.2794)
			(stroke
				(width 0.1)
				(type default)
			)
			(layer "F.Fab")
		)
		(fp_line
			(start 0.67945 0.3048)
			(end 0.120396 0.3048)
			(stroke
				(width 0.1)
				(type default)
			)
			(layer "F.Fab")
		)
		(fp_line
			(start -0.12065 0.2794)
			(end -0.12065 0.3048)
			(stroke
				(width 0.1)
				(type default)
			)
			(layer "F.Fab")
		)
		(fp_line
			(start 0.120396 0.2794)
			(end -0.12065 0.2794)
			(stroke
				(width 0.1)
				(type default)
			)
			(layer "F.Fab")
		)
		(fp_line
			(start -0.12065 -0.2794)
			(end 0.12065 -0.2794)
			(stroke
				(width 0.1)
				(type default)
			)
			(layer "F.Fab")
		)
		(fp_line
			(start 0.12065 -0.2794)
			(end 0.12065 -0.3048)
			(stroke
				(width 0.1)
				(type default)
			)
			(layer "F.Fab")
		)
		(fp_line
			(start 0.12065 -0.3048)
			(end 0.67945 -0.3048)
			(stroke
				(width 0.1)
				(type default)
			)
			(layer "F.Fab")
		)
		(fp_line
			(start 0.67945 -0.3048)
			(end 0.67945 0.3048)
			(stroke
				(width 0.1)
				(type default)
			)
			(layer "F.Fab")
		)
		(fp_line
			(start -0.67945 -0.305054)
			(end -0.12065 -0.305054)
			(stroke
				(width 0.1)
				(type default)
			)
			(layer "F.Fab")
		)
		(fp_line
			(start -0.12065 -0.305054)
			(end -0.12065 -0.2794)
			(stroke
				(width 0.1)
				(type default)
			)
			(layer "F.Fab")
		)
		(pad "1" smd circle
			(at -0.40005 0 270)
			(size 0 0)
			(layers "F.Cu" "F.Mask" "F.Paste")
			(net "SW_P12V_PVCCINFAON_CPU0_FLT")
		)
		(pad "2" smd circle
			(at 0.40005 0 270)
			(size 0 0)
			(layers "F.Cu" "F.Mask" "F.Paste")
			(net "GND")
		)
	)
	(footprint ""
		(layer "F.Cu")
		(at 69.923406 -154.36469)
		(property "Reference" "PC1596"
			(at 0 0 0)
			(layer "F.SilkS")
			(hide yes)
			(effects
				(font
					(size 1.27 1.27)
				)
			)
		)
		(property "Value" ""
			(at 0 0 0)
			(layer "F.Fab")
			(effects
				(font
					(size 1.27 1.27)
				)
			)
		)
		(duplicate_pad_numbers_are_jumpers no)
		(fp_line
			(start 2.750058 0.999998)
			(end -2.750058 0.999998)
			(stroke
				(width 0.1524)
				(type default)
			)
			(layer "F.SilkS")
		)
		(fp_circle
			(center 0 0.999998)
			(end 2.750058 0.999998)
			(stroke
				(width 0.1524)
				(type default)
			)
			(fill no)
			(layer "F.SilkS")
		)
		(fp_poly
			(pts
				(arc
					(start 2.750058 0.999998)
					(mid 0 3.750056)
					(end -2.750058 0.999998)
				)
			)
			(stroke
				(width 0)
				(type default)
			)
			(fill yes)
			(layer "F.SilkS")
		)
		(fp_circle
			(center 0 0.999998)
			(end 2.750058 0.999998)
			(stroke
				(width 0.1)
				(type default)
			)
			(fill no)
			(layer "F.Fab")
		)
		(pad "1" thru_hole rect
			(at 0 0)
			(size 1.5748 1.5748)
			(drill 1.0668)
			(layers "*.Cu" "*.Mask")
			(remove_unused_layers no)
			(net "PVCCINFAON_CPU1")
			(clearance 0)
			(padstack
				(mode front_inner_back)
				(layer "Inner"
					(shape circle)
					(size 1.5748 1.5748)
					(clearance 0)
				)
				(layer "B.Cu"
					(shape rect)
					(size 1.5748 1.5748)
					(clearance 0)
				)
			)
		)
		(pad "2" thru_hole circle
			(at 0 1.999996)
			(size 1.5748 1.5748)
			(drill 1.0668)
			(layers "*.Cu" "*.Mask")
			(remove_unused_layers no)
			(net "GND")
			(clearance 0)
		)
	)
)
